(kicad_pcb
	(version 20260206)
	(generator "pcbnew")
	(generator_version "10.0")
	(general
		(thickness 1.6)
		(legacy_teardrops no)
	)
	(paper "A4")
	(title_block
		(title "timecard-production-celestica-r4006 — R4006-B0001-02_R01.brd")
		(comment 1 "Time Appliance Project (Time Card) / footprints 1012-1017 of 1113")
	)
	(layers
		(0 "F.Cu" signal "TOP")
		(4 "In1.Cu" signal "L02_GND1")
		(6 "In2.Cu" signal "L03_SIG1")
		(8 "In3.Cu" signal "L04_GND2")
		(10 "In4.Cu" signal "L05_VCC1")
		(12 "In5.Cu" signal "L06_VCC2")
		(14 "In6.Cu" signal "L07_GND3")
		(16 "In7.Cu" signal "L08_SIG2")
		(18 "In8.Cu" signal "L09_GND4")
		(2 "B.Cu" signal "BOTTOM")
		(9 "F.Adhes" user "F.Adhesive")
		(11 "B.Adhes" user "B.Adhesive")
		(13 "F.Paste" user "Package Geometry/Pastemask Top")
		(15 "B.Paste" user "Package Geometry/Pastemask Bottom")
		(5 "F.SilkS" user "Ref Des/Silkscreen Top")
		(7 "B.SilkS" user "Ref Des/Silkscreen Bottom")
		(1 "F.Mask" user "Board Geometry/Soldermask Top")
		(3 "B.Mask" user "Board Geometry/Soldermask Bottom")
		(17 "Dwgs.User" user "User.Drawings")
		(19 "Cmts.User" user "User.Comments")
		(21 "Eco1.User" user "User.Eco1")
		(23 "Eco2.User" user "User.Eco2")
		(25 "Edge.Cuts" user "Board Geometry/Outline")
		(27 "Margin" user)
		(31 "F.CrtYd" user "Package Geometry/Place Bound Top")
		(29 "B.CrtYd" user "Package Geometry/Place Bound Bottom")
		(35 "F.Fab" user "Ref Des/Assembly Top")
		(33 "B.Fab" user "Ref Des/Assembly Bottom")
	)
	(footprint ""
		(layer "B.Cu")
		(at 83.2358 -82.55 180)
		(property "Reference" "R152"
			(at 0.1778 -2.32537 0)
			(unlocked yes)
			(layer "B.SilkS")
			(effects
				(font
					(size 0.7874 0.5842)
					(thickness 0.1524)
				)
				(justify mirror)
			)
		)
		(property "Value" "VAL*"
			(at -0.02032 2.13233 180)
			(unlocked yes)
			(layer "B.Fab")
			(hide yes)
			(effects
				(font
					(size 0.7874 0.5842)
					(thickness 0.1524)
				)
				(justify mirror)
			)
		)
		(property "Tolerance" "TOL*"
			(at -0.044704 3.05435 180)
			(unlocked yes)
			(layer "Cmts.User")
			(hide yes)
			(effects
				(font
					(size 0.7874 0.5842)
					(thickness 0.1524)
				)
				(justify mirror)
			)
		)
		(property "User Part Number" "PARTNUM*"
			(at -0.02032 4.024884 180)
			(unlocked yes)
			(layer "Cmts.User")
			(hide yes)
			(effects
				(font
					(size 0.7874 0.5842)
					(thickness 0.1524)
				)
				(justify mirror)
			)
		)
		(property "Device Type" "RESISTOR-G155-14701-01,4.7KOHMA"
			(at -0.008382 1.210564 180)
			(unlocked yes)
			(layer "B.Fab")
			(hide yes)
			(effects
				(font
					(size 0.7874 0.5842)
					(thickness 0.1524)
				)
				(justify mirror)
			)
		)
		(duplicate_pad_numbers_are_jumpers no)
		(fp_line
			(start 1.143 0.5588)
			(end -1.143 0.5588)
			(stroke
				(width 0.1)
				(type default)
			)
			(layer "B.SilkS")
		)
		(fp_line
			(start 1.143 -0.5588)
			(end 1.143 0.5588)
			(stroke
				(width 0.1)
				(type default)
			)
			(layer "B.SilkS")
		)
		(fp_line
			(start -1.143 0.5588)
			(end -1.143 -0.5588)
			(stroke
				(width 0.1)
				(type default)
			)
			(layer "B.SilkS")
		)
		(fp_line
			(start -1.143 -0.5588)
			(end 1.143 -0.5588)
			(stroke
				(width 0.1)
				(type default)
			)
			(layer "B.SilkS")
		)
		(fp_rect
			(start -1.143 0.5588)
			(end 1.143 -0.5588)
			(stroke
				(width 0)
				(type default)
			)
			(fill no)
			(layer "B.CrtYd")
		)
		(fp_line
			(start 0.508 0.3048)
			(end -0.508 0.3048)
			(stroke
				(width 0.1)
				(type default)
			)
			(layer "B.Fab")
		)
		(fp_line
			(start 0.508 -0.3048)
			(end 0.508 0.3048)
			(stroke
				(width 0.1)
				(type default)
			)
			(layer "B.Fab")
		)
		(fp_line
			(start -0.508 0.3048)
			(end -0.508 -0.3048)
			(stroke
				(width 0.1)
				(type default)
			)
			(layer "B.Fab")
		)
		(fp_line
			(start -0.508 -0.3048)
			(end 0.508 -0.3048)
			(stroke
				(width 0.1)
				(type default)
			)
			(layer "B.Fab")
		)
		(pad "1" smd rect
			(at 0.5334 0)
			(size 0.7112 0.6096)
			(layers "B.Cu" "B.Mask" "B.Paste")
			(net "SG")
		)
		(pad "2" smd rect
			(at -0.5334 0)
			(size 0.7112 0.6096)
			(layers "B.Cu" "B.Mask" "B.Paste")
			(net "UNNAMED_5_PCA9546APWTSSOP16_I33")
		)
		(zone
			(layer "B.Cu")
			(hatch none 0.5)
			(connect_pads
				(clearance 0)
			)
			(min_thickness 0.25)
			(keepout
				(tracks allowed)
				(vias not_allowed)
				(pads allowed)
				(copperpour not_allowed)
				(footprints allowed)
			)
			(placement
				(enabled no)
				(sheetname "")
			)
			(fill
				(thermal_gap 0.5)
				(thermal_bridge_width 0.5)
				(island_removal_mode 0)
			)
			(polygon
				(pts
					(xy 83.312 -82.8548) (xy 83.1596 -82.8548) (xy 83.1596 -82.2452) (xy 83.312 -82.2452)
				)
			)
		)
	)
	(footprint ""
		(layer "B.Cu")
		(at 75.514962 -15.367 -90)
		(property "Reference" "C35"
			(at -1.778 -2.372868 270)
			(unlocked yes)
			(layer "B.SilkS")
			(effects
				(font
					(size 0.7874 0.5842)
					(thickness 0.1524)
				)
				(justify mirror)
			)
		)
		(property "Value" "VAL*"
			(at -0.0762 2.067306 270)
			(unlocked yes)
			(layer "B.Fab")
			(hide yes)
			(effects
				(font
					(size 0.7874 0.5842)
					(thickness 0.1524)
				)
				(justify mirror)
			)
		)
		(property "Tolerance" "TOL*"
			(at -0.0762 3.032506 270)
			(unlocked yes)
			(layer "Cmts.User")
			(hide yes)
			(effects
				(font
					(size 0.7874 0.5842)
					(thickness 0.1524)
				)
				(justify mirror)
			)
		)
		(property "User Part Number" "PARTNUM*"
			(at -0.1016 4.023106 270)
			(unlocked yes)
			(layer "Cmts.User")
			(hide yes)
			(effects
				(font
					(size 0.7874 0.5842)
					(thickness 0.1524)
				)
				(justify mirror)
			)
		)
		(property "Device Type" "CAPACITOR-G105-0B104-CK,0.1UF,A"
			(at -0.0508 1.127506 270)
			(unlocked yes)
			(layer "B.Fab")
			(hide yes)
			(effects
				(font
					(size 0.7874 0.5842)
					(thickness 0.1524)
				)
				(justify mirror)
			)
		)
		(duplicate_pad_numbers_are_jumpers no)
		(fp_line
			(start -1.143 0.5588)
			(end -1.143 -0.5588)
			(stroke
				(width 0.1)
				(type default)
			)
			(layer "B.SilkS")
		)
		(fp_line
			(start 1.143 0.5588)
			(end -1.143 0.5588)
			(stroke
				(width 0.1)
				(type default)
			)
			(layer "B.SilkS")
		)
		(fp_line
			(start -1.143 -0.5588)
			(end 1.143 -0.5588)
			(stroke
				(width 0.1)
				(type default)
			)
			(layer "B.SilkS")
		)
		(fp_line
			(start 1.143 -0.5588)
			(end 1.143 0.5588)
			(stroke
				(width 0.1)
				(type default)
			)
			(layer "B.SilkS")
		)
		(fp_rect
			(start 1.143 0.5588)
			(end -1.143 -0.5588)
			(stroke
				(width 0)
				(type default)
			)
			(fill no)
			(layer "B.CrtYd")
		)
		(fp_line
			(start -0.508 0.3048)
			(end -0.508 -0.3048)
			(stroke
				(width 0.1)
				(type default)
			)
			(layer "B.Fab")
		)
		(fp_line
			(start 0.508 0.3048)
			(end -0.508 0.3048)
			(stroke
				(width 0.1)
				(type default)
			)
			(layer "B.Fab")
		)
		(fp_line
			(start -0.508 -0.3048)
			(end 0.508 -0.3048)
			(stroke
				(width 0.1)
				(type default)
			)
			(layer "B.Fab")
		)
		(fp_line
			(start 0.508 -0.3048)
			(end 0.508 0.3048)
			(stroke
				(width 0.1)
				(type default)
			)
			(layer "B.Fab")
		)
		(pad "1" smd rect
			(at 0.5334 0 90)
			(size 0.7112 0.6096)
			(layers "B.Cu" "B.Mask" "B.Paste")
			(net "C_CPU_RX_PCIE_MGT3_TXP")
		)
		(pad "2" smd rect
			(at -0.5334 0 90)
			(size 0.7112 0.6096)
			(layers "B.Cu" "B.Mask" "B.Paste")
			(net "CPU_RX_PCIE_MGT3_TXP")
		)
		(zone
			(layer "B.Cu")
			(hatch none 0.5)
			(connect_pads
				(clearance 0)
			)
			(min_thickness 0.25)
			(keepout
				(tracks allowed)
				(vias not_allowed)
				(pads allowed)
				(copperpour not_allowed)
				(footprints allowed)
			)
			(placement
				(enabled no)
				(sheetname "")
			)
			(fill
				(thermal_gap 0.5)
				(thermal_bridge_width 0.5)
				(island_removal_mode 0)
			)
			(polygon
				(pts
					(xy 75.210162 -15.2908) (xy 75.819762 -15.2908) (xy 75.819762 -15.4432) (xy 75.210162 -15.4432)
				)
			)
		)
	)
	(footprint ""
		(layer "B.Cu")
		(at 140.2842 -74.2315)
		(property "Reference" "R136"
			(at 0.4318 -1.04013 0)
			(unlocked yes)
			(layer "B.SilkS")
			(effects
				(font
					(size 0.7874 0.5842)
					(thickness 0.1524)
				)
				(justify mirror)
			)
		)
		(property "Value" "VAL*"
			(at -0.02032 2.13233 0)
			(unlocked yes)
			(layer "B.Fab")
			(hide yes)
			(effects
				(font
					(size 0.7874 0.5842)
					(thickness 0.1524)
				)
				(justify mirror)
			)
		)
		(property "Tolerance" "TOL*"
			(at -0.044704 3.05435 0)
			(unlocked yes)
			(layer "Cmts.User")
			(hide yes)
			(effects
				(font
					(size 0.7874 0.5842)
					(thickness 0.1524)
				)
				(justify mirror)
			)
		)
		(property "User Part Number" "PARTNUM*"
			(at -0.02032 4.024884 0)
			(unlocked yes)
			(layer "Cmts.User")
			(hide yes)
			(effects
				(font
					(size 0.7874 0.5842)
					(thickness 0.1524)
				)
				(justify mirror)
			)
		)
		(property "Device Type" "RESISTOR-G155-133R0-01,33OHM,1%"
			(at -0.008382 1.210564 0)
			(unlocked yes)
			(layer "B.Fab")
			(hide yes)
			(effects
				(font
					(size 0.7874 0.5842)
					(thickness 0.1524)
				)
				(justify mirror)
			)
		)
		(duplicate_pad_numbers_are_jumpers no)
		(fp_line
			(start -1.143 -0.5588)
			(end 1.143 -0.5588)
			(stroke
				(width 0.1)
				(type default)
			)
			(layer "B.SilkS")
		)
		(fp_line
			(start -1.143 0.5588)
			(end -1.143 -0.5588)
			(stroke
				(width 0.1)
				(type default)
			)
			(layer "B.SilkS")
		)
		(fp_line
			(start 1.143 -0.5588)
			(end 1.143 0.5588)
			(stroke
				(width 0.1)
				(type default)
			)
			(layer "B.SilkS")
		)
		(fp_line
			(start 1.143 0.5588)
			(end -1.143 0.5588)
			(stroke
				(width 0.1)
				(type default)
			)
			(layer "B.SilkS")
		)
		(fp_rect
			(start -1.143 -0.5588)
			(end 1.143 0.5588)
			(stroke
				(width 0)
				(type default)
			)
			(fill no)
			(layer "B.CrtYd")
		)
		(fp_line
			(start -0.508 -0.3048)
			(end 0.508 -0.3048)
			(stroke
				(width 0.1)
				(type default)
			)
			(layer "B.Fab")
		)
		(fp_line
			(start -0.508 0.3048)
			(end -0.508 -0.3048)
			(stroke
				(width 0.1)
				(type default)
			)
			(layer "B.Fab")
		)
		(fp_line
			(start 0.508 -0.3048)
			(end 0.508 0.3048)
			(stroke
				(width 0.1)
				(type default)
			)
			(layer "B.Fab")
		)
		(fp_line
			(start 0.508 0.3048)
			(end -0.508 0.3048)
			(stroke
				(width 0.1)
				(type default)
			)
			(layer "B.Fab")
		)
		(pad "1" smd rect
			(at 0.5334 0 180)
			(size 0.7112 0.6096)
			(layers "B.Cu" "B.Mask" "B.Paste")
			(net "FT4232_FPGA_TMS")
		)
		(pad "2" smd rect
			(at -0.5334 0 180)
			(size 0.7112 0.6096)
			(layers "B.Cu" "B.Mask" "B.Paste")
			(net "FPGA_TMS")
		)
		(zone
			(layer "B.Cu")
			(hatch none 0.5)
			(connect_pads
				(clearance 0)
			)
			(min_thickness 0.25)
			(keepout
				(tracks allowed)
				(vias not_allowed)
				(pads allowed)
				(copperpour not_allowed)
				(footprints allowed)
			)
			(placement
				(enabled no)
				(sheetname "")
			)
			(fill
				(thermal_gap 0.5)
				(thermal_bridge_width 0.5)
				(island_removal_mode 0)
			)
			(polygon
				(pts
					(xy 140.208 -74.5363) (xy 140.208 -73.9267) (xy 140.3604 -73.9267) (xy 140.3604 -74.5363)
				)
			)
		)
	)
	(footprint ""
		(layer "B.Cu")
		(at 102.84714 -41.32326 -90)
		(property "Reference" "C105"
			(at 1.016 41.50995 270)
			(unlocked yes)
			(layer "B.SilkS")
			(effects
				(font
					(size 0.635 0.4064)
					(thickness 0.1524)
				)
				(justify mirror)
			)
		)
		(property "Value" "VAL*"
			(at 0 3.718306 270)
			(unlocked yes)
			(layer "B.Fab")
			(hide yes)
			(effects
				(font
					(size 0.7874 0.5842)
					(thickness 0.127)
				)
				(justify mirror)
			)
		)
		(property "Tolerance" "TOL*"
			(at 0 4.861306 270)
			(unlocked yes)
			(layer "Cmts.User")
			(hide yes)
			(effects
				(font
					(size 0.7874 0.5842)
					(thickness 0.127)
				)
				(justify mirror)
			)
		)
		(property "User Part Number" "PARTNUM*"
			(at 0 2.575306 270)
			(unlocked yes)
			(layer "Cmts.User")
			(hide yes)
			(effects
				(font
					(size 0.7874 0.5842)
					(thickness 0.127)
				)
				(justify mirror)
			)
		)
		(property "Device Type" "CAPACITOR-G105-0B104-CK,0.1UF,A"
			(at 0 1.432306 270)
			(unlocked yes)
			(layer "B.Fab")
			(hide yes)
			(effects
				(font
					(size 0.7874 0.5842)
					(thickness 0.127)
				)
				(justify mirror)
			)
		)
		(duplicate_pad_numbers_are_jumpers no)
		(fp_line
			(start -0.970026 0.4699)
			(end 0.970026 0.4699)
			(stroke
				(width 0.1)
				(type default)
			)
			(layer "B.SilkS")
		)
		(fp_line
			(start 0.970026 0.4699)
			(end 0.970026 -0.4699)
			(stroke
				(width 0.1)
				(type default)
			)
			(layer "B.SilkS")
		)
		(fp_line
			(start -0.970026 -0.4699)
			(end -0.970026 0.4699)
			(stroke
				(width 0.1)
				(type default)
			)
			(layer "B.SilkS")
		)
		(fp_line
			(start 0.970026 -0.4699)
			(end -0.970026 -0.4699)
			(stroke
				(width 0.1)
				(type default)
			)
			(layer "B.SilkS")
		)
		(fp_poly
			(pts
				(xy 0.970026 0.4699) (xy -0.970026 0.4699) (xy -0.970026 -0.4699) (xy 0.970026 -0.4699)
			)
			(stroke
				(width 0)
				(type default)
			)
			(fill no)
			(layer "B.CrtYd")
		)
		(fp_line
			(start -0.508 0.3048)
			(end 0.508 0.3048)
			(stroke
				(width 0.1)
				(type default)
			)
			(layer "B.Fab")
		)
		(fp_line
			(start 0.508 0.3048)
			(end 0.508 -0.3048)
			(stroke
				(width 0.1)
				(type default)
			)
			(layer "B.Fab")
		)
		(fp_line
			(start -0.508 -0.3048)
			(end -0.508 0.3048)
			(stroke
				(width 0.1)
				(type default)
			)
			(layer "B.Fab")
		)
		(fp_line
			(start 0.508 -0.3048)
			(end -0.508 -0.3048)
			(stroke
				(width 0.1)
				(type default)
			)
			(layer "B.Fab")
		)
		(pad "1" smd circle
			(at 0.500126 0 90)
			(size 0.635 0.635)
			(layers "B.Cu" "B.Mask" "B.Paste")
			(net "XP1R0V_FPGA_MGTAVCC")
		)
		(pad "2" smd circle
			(at -0.500126 0 90)
			(size 0.635 0.635)
			(layers "B.Cu" "B.Mask" "B.Paste")
			(net "SG")
		)
	)
	(footprint ""
		(layer "B.Cu")
		(at 112.880394 -44.577 180)
		(property "Reference" "C128"
			(at 43.307254 -1.88595 0)
			(unlocked yes)
			(layer "B.SilkS")
			(effects
				(font
					(size 0.635 0.4064)
					(thickness 0.1524)
				)
				(justify mirror)
			)
		)
		(property "Value" "VAL*"
			(at -0.02032 2.13233 180)
			(unlocked yes)
			(layer "B.Fab")
			(hide yes)
			(effects
				(font
					(size 0.7874 0.5842)
					(thickness 0.1524)
				)
				(justify mirror)
			)
		)
		(property "Device Type" "CAPACITOR-G105-0F475-BM,4.7UF,A"
			(at -0.008382 1.210564 180)
			(unlocked yes)
			(layer "B.Fab")
			(hide yes)
			(effects
				(font
					(size 0.7874 0.5842)
					(thickness 0.1524)
				)
				(justify mirror)
			)
		)
		(property "User Part Number" "PARTNUM*"
			(at -0.02032 4.024884 180)
			(unlocked yes)
			(layer "Cmts.User")
			(hide yes)
			(effects
				(font
					(size 0.7874 0.5842)
					(thickness 0.1524)
				)
				(justify mirror)
			)
		)
		(property "Tolerance" "TOL*"
			(at -0.044704 3.05435 180)
			(unlocked yes)
			(layer "Cmts.User")
			(hide yes)
			(effects
				(font
					(size 0.7874 0.5842)
					(thickness 0.1524)
				)
				(justify mirror)
			)
		)
		(duplicate_pad_numbers_are_jumpers no)
		(fp_line
			(start 1.143 0.5588)
			(end -1.143 0.5588)
			(stroke
				(width 0.1)
				(type default)
			)
			(layer "B.SilkS")
		)
		(fp_line
			(start 1.143 -0.5588)
			(end 1.143 0.5588)
			(stroke
				(width 0.1)
				(type default)
			)
			(layer "B.SilkS")
		)
		(fp_line
			(start -1.143 0.5588)
			(end -1.143 -0.5588)
			(stroke
				(width 0.1)
				(type default)
			)
			(layer "B.SilkS")
		)
		(fp_line
			(start -1.143 -0.5588)
			(end 1.143 -0.5588)
			(stroke
				(width 0.1)
				(type default)
			)
			(layer "B.SilkS")
		)
		(fp_rect
			(start 1.143 -0.5588)
			(end -1.143 0.5588)
			(stroke
				(width 0)
				(type default)
			)
			(fill no)
			(layer "B.CrtYd")
		)
		(fp_line
			(start 0.508 0.3048)
			(end -0.508 0.3048)
			(stroke
				(width 0.1)
				(type default)
			)
			(layer "B.Fab")
		)
		(fp_line
			(start 0.508 -0.3048)
			(end 0.508 0.3048)
			(stroke
				(width 0.1)
				(type default)
			)
			(layer "B.Fab")
		)
		(fp_line
			(start -0.508 0.3048)
			(end -0.508 -0.3048)
			(stroke
				(width 0.1)
				(type default)
			)
			(layer "B.Fab")
		)
		(fp_line
			(start -0.508 -0.3048)
			(end 0.508 -0.3048)
			(stroke
				(width 0.1)
				(type default)
			)
			(layer "B.Fab")
		)
		(pad "1" smd rect
			(at 0.5334 0)
			(size 0.7112 0.6096)
			(layers "B.Cu" "B.Mask" "B.Paste")
			(net "XP1R8V_FPGA_VCCAUX")
		)
		(pad "2" smd rect
			(at -0.5334 0)
			(size 0.7112 0.6096)
			(layers "B.Cu" "B.Mask" "B.Paste")
			(net "SG")
		)
		(zone
			(layer "B.Cu")
			(hatch none 0.5)
			(connect_pads
				(clearance 0)
			)
			(min_thickness 0.25)
			(keepout
				(tracks allowed)
				(vias not_allowed)
				(pads allowed)
				(copperpour not_allowed)
				(footprints allowed)
			)
			(placement
				(enabled no)
				(sheetname "")
			)
			(fill
				(thermal_gap 0.5)
				(thermal_bridge_width 0.5)
				(island_removal_mode 0)
			)
			(polygon
				(pts
					(xy 112.804194 -44.2722) (xy 112.956594 -44.2722) (xy 112.956594 -44.8818) (xy 112.804194 -44.8818)
				)
			)
		)
	)
	(footprint ""
		(layer "B.Cu")
		(at 90.7542 -106.6038 180)
		(property "Reference" "R263"
			(at 0.5842 2.19583 0)
			(unlocked yes)
			(layer "B.SilkS")
			(effects
				(font
					(size 0.7874 0.5842)
					(thickness 0.1524)
				)
				(justify mirror)
			)
		)
		(property "Value" "VAL*"
			(at -0.02032 2.13233 180)
			(unlocked yes)
			(layer "B.Fab")
			(hide yes)
			(effects
				(font
					(size 0.7874 0.5842)
					(thickness 0.1524)
				)
				(justify mirror)
			)
		)
		(property "Tolerance" "TOL*"
			(at -0.044704 3.05435 180)
			(unlocked yes)
			(layer "Cmts.User")
			(hide yes)
			(effects
				(font
					(size 0.7874 0.5842)
					(thickness 0.1524)
				)
				(justify mirror)
			)
		)
		(property "User Part Number" "PARTNUM*"
			(at -0.02032 4.024884 180)
			(unlocked yes)
			(layer "Cmts.User")
			(hide yes)
			(effects
				(font
					(size 0.7874 0.5842)
					(thickness 0.1524)
				)
				(justify mirror)
			)
		)
		(property "Device Type" "RESISTOR-G155-100R0-J0,0OHM,-"
			(at -0.008382 1.210564 180)
			(unlocked yes)
			(layer "B.Fab")
			(hide yes)
			(effects
				(font
					(size 0.7874 0.5842)
					(thickness 0.1524)
				)
				(justify mirror)
			)
		)
		(duplicate_pad_numbers_are_jumpers no)
		(fp_line
			(start 1.143 0.5588)
			(end -1.143 0.5588)
			(stroke
				(width 0.1)
				(type default)
			)
			(layer "B.SilkS")
		)
		(fp_line
			(start 1.143 -0.5588)
			(end 1.143 0.5588)
			(stroke
				(width 0.1)
				(type default)
			)
			(layer "B.SilkS")
		)
		(fp_line
			(start -1.143 0.5588)
			(end -1.143 -0.5588)
			(stroke
				(width 0.1)
				(type default)
			)
			(layer "B.SilkS")
		)
		(fp_line
			(start -1.143 -0.5588)
			(end 1.143 -0.5588)
			(stroke
				(width 0.1)
				(type default)
			)
			(layer "B.SilkS")
		)
		(fp_rect
			(start -1.143 0.5588)
			(end 1.143 -0.5588)
			(stroke
				(width 0)
				(type default)
			)
			(fill no)
			(layer "B.CrtYd")
		)
		(fp_line
			(start 0.508 0.3048)
			(end -0.508 0.3048)
			(stroke
				(width 0.1)
				(type default)
			)
			(layer "B.Fab")
		)
		(fp_line
			(start 0.508 -0.3048)
			(end 0.508 0.3048)
			(stroke
				(width 0.1)
				(type default)
			)
			(layer "B.Fab")
		)
		(fp_line
			(start -0.508 0.3048)
			(end -0.508 -0.3048)
			(stroke
				(width 0.1)
				(type default)
			)
			(layer "B.Fab")
		)
		(fp_line
			(start -0.508 -0.3048)
			(end 0.508 -0.3048)
			(stroke
				(width 0.1)
				(type default)
			)
			(layer "B.Fab")
		)
		(pad "1" smd rect
			(at 0.5334 0)
			(size 0.7112 0.6096)
			(layers "B.Cu" "B.Mask" "B.Paste")
			(net "R_XP3R3V_PG")
		)
		(pad "2" smd rect
			(at -0.5334 0)
			(size 0.7112 0.6096)
			(layers "B.Cu" "B.Mask" "B.Paste")
			(net "XP3R3V_PG")
		)
		(zone
			(layer "B.Cu")
			(hatch none 0.5)
			(connect_pads
				(clearance 0)
			)
			(min_thickness 0.25)
			(keepout
				(tracks allowed)
				(vias not_allowed)
				(pads allowed)
				(copperpour not_allowed)
				(footprints allowed)
			)
			(placement
				(enabled no)
				(sheetname "")
			)
			(fill
				(thermal_gap 0.5)
				(thermal_bridge_width 0.5)
				(island_removal_mode 0)
			)
			(polygon
				(pts
					(xy 90.8304 -106.9086) (xy 90.678 -106.9086) (xy 90.678 -106.299) (xy 90.8304 -106.299)
				)
			)
		)
	)
)
